(kicad_pcb
	(version 20260206)
	(generator "pcbnew")
	(generator_version "10.0")
	(general
		(thickness 1.6)
		(legacy_teardrops no)
	)
	(paper "A4")
	(title_block
		(title "peb — Lightning_PEB_BRD.brd")
		(comment 1 "Lightning (Wiwynn / Facebook NVMe JBOF) / footprints 1320-1326 of 2563")
	)
	(layers
		(0 "F.Cu" signal "TOP")
		(4 "In1.Cu" signal "L2GND")
		(6 "In2.Cu" signal "L3")
		(8 "In3.Cu" signal "L4VCC")
		(10 "In4.Cu" signal "L5VCC")
		(12 "In5.Cu" signal "L6")
		(14 "In6.Cu" signal "L7GND")
		(2 "B.Cu" signal "BOTTOM")
		(9 "F.Adhes" user "F.Adhesive")
		(11 "B.Adhes" user "B.Adhesive")
		(13 "F.Paste" user "Package Geometry/Pastemask Top")
		(15 "B.Paste" user "Package Geometry/Pastemask Bottom")
		(5 "F.SilkS" user "Ref Des/Silkscreen Top")
		(7 "B.SilkS" user "Ref Des/Silkscreen Bottom")
		(1 "F.Mask" user "Board Geometry/Soldermask Top")
		(3 "B.Mask" user "Board Geometry/Soldermask Bottom")
		(17 "Dwgs.User" user "User.Drawings")
		(19 "Cmts.User" user "User.Comments")
		(21 "Eco1.User" user "User.Eco1")
		(23 "Eco2.User" user "User.Eco2")
		(25 "Edge.Cuts" user "Board Geometry/Outline")
		(27 "Margin" user)
		(31 "F.CrtYd" user "Package Geometry/Place Bound Top")
		(29 "B.CrtYd" user "Package Geometry/Place Bound Bottom")
		(35 "F.Fab" user "Ref Des/Assembly Top")
		(33 "B.Fab" user "Ref Des/Assembly Bottom")
	)
	(footprint ""
		(layer "F.Cu")
		(at 264.583418 -2.869184 -90)
		(property "Reference" "R7917"
			(at 0 0 270)
			(layer "F.SilkS")
			(hide yes)
			(effects
				(font
					(size 1.27 1.27)
				)
			)
		)
		(property "Value" "0R2J-2-GP"
			(at 0.064008 -3.993896 270)
			(unlocked yes)
			(layer "F.Fab")
			(hide yes)
			(effects
				(font
					(size 1.016 1.016)
					(thickness 0.1524)
				)
			)
		)
		(property "Device Type" "R402H16"
			(at 0.064008 -5.517896 270)
			(unlocked yes)
			(layer "F.Fab")
			(hide yes)
			(effects
				(font
					(size 1.016 1.016)
					(thickness 0.1524)
				)
			)
		)
		(duplicate_pad_numbers_are_jumpers no)
		(fp_line
			(start -0.508 -0.9398)
			(end -0.508 0.9398)
			(stroke
				(width 0.1524)
				(type default)
			)
			(layer "F.SilkS")
		)
		(fp_line
			(start 0.508 -0.9398)
			(end -0.508 -0.9398)
			(stroke
				(width 0.1524)
				(type default)
			)
			(layer "F.SilkS")
		)
		(fp_rect
			(start -0.508 0.9398)
			(end 0.508 -0.9398)
			(stroke
				(width 0)
				(type default)
			)
			(fill no)
			(layer "F.CrtYd")
		)
		(fp_rect
			(start -0.508 0.9398)
			(end 0.508 -0.9398)
			(stroke
				(width 0)
				(type default)
			)
			(fill no)
			(layer "F.Fab")
		)
		(pad "1" smd custom
			(at 0 -0.4445 270)
			(size 0.1397 0.1397)
			(layers "F.Cu" "F.Mask" "F.Paste")
			(net "RST_BTN#_R")
			(options
				(clearance outline)
				(anchor circle)
			)
			(primitives
				(gr_poly
					(pts
						(arc
							(start -0.1778 -0.2794)
							(mid -0.249642 -0.249642)
							(end -0.2794 -0.1778)
						)
						(arc
							(start -0.2794 0.1778)
							(mid -0.249642 0.249642)
							(end -0.1778 0.2794)
						)
						(arc
							(start 0.1778 0.2794)
							(mid 0.249642 0.249642)
							(end 0.2794 0.1778)
						)
						(arc
							(start 0.2794 -0.1778)
							(mid 0.249642 -0.249642)
							(end 0.1778 -0.2794)
						)
					)
					(width 0)
					(fill yes)
				)
			)
		)
		(pad "2" smd custom
			(at 0 0.4445 270)
			(size 0.1397 0.1397)
			(layers "F.Cu" "F.Mask" "F.Paste")
			(net "RST_BTN#")
			(options
				(clearance outline)
				(anchor circle)
			)
			(primitives
				(gr_poly
					(pts
						(arc
							(start -0.1778 -0.2794)
							(mid -0.249642 -0.249642)
							(end -0.2794 -0.1778)
						)
						(arc
							(start -0.2794 0.1778)
							(mid -0.249642 0.249642)
							(end -0.1778 0.2794)
						)
						(arc
							(start 0.1778 0.2794)
							(mid 0.249642 0.249642)
							(end 0.2794 0.1778)
						)
						(arc
							(start 0.2794 -0.1778)
							(mid 0.249642 -0.249642)
							(end 0.1778 -0.2794)
						)
					)
					(width 0)
					(fill yes)
				)
			)
		)
	)
	(footprint ""
		(layer "F.Cu")
		(at 284.861 -57.15 180)
		(property "Reference" "Q33"
			(at 0 0 180)
			(layer "F.SilkS")
			(hide yes)
			(effects
				(font
					(size 1.27 1.27)
				)
			)
		)
		(property "Value" "2N7002K-1-GP"
			(at 0.127 -8.9662 180)
			(unlocked yes)
			(layer "F.Fab")
			(hide yes)
			(effects
				(font
					(size 1.016 1.016)
					(thickness 0.1524)
				)
			)
		)
		(property "Device Type" "SOT23DGS2D4H44"
			(at 0.127 -10.4902 180)
			(unlocked yes)
			(layer "F.Fab")
			(hide yes)
			(effects
				(font
					(size 1.016 1.016)
					(thickness 0.1524)
				)
			)
		)
		(duplicate_pad_numbers_are_jumpers no)
		(fp_line
			(start 1.651 1.778)
			(end 1.651 -1.778)
			(stroke
				(width 0.1524)
				(type default)
			)
			(layer "F.SilkS")
		)
		(fp_line
			(start 1.651 -1.778)
			(end -1.651 -1.778)
			(stroke
				(width 0.1524)
				(type default)
			)
			(layer "F.SilkS")
		)
		(fp_line
			(start -1.651 1.778)
			(end 1.651 1.778)
			(stroke
				(width 0.1524)
				(type default)
			)
			(layer "F.SilkS")
		)
		(fp_line
			(start -1.651 -1.778)
			(end -1.651 1.778)
			(stroke
				(width 0.1524)
				(type default)
			)
			(layer "F.SilkS")
		)
		(fp_poly
			(pts
				(xy -1.778 1.8796) (xy -1.778 -1.8796) (xy 1.778 -1.8796) (xy 1.778 1.8796)
			)
			(stroke
				(width 0)
				(type default)
			)
			(fill no)
			(layer "F.CrtYd")
		)
		(fp_poly
			(pts
				(xy -1.778 1.8796) (xy -1.778 -1.8796) (xy 1.778 -1.8796) (xy 1.778 1.8796)
			)
			(stroke
				(width 0)
				(type default)
			)
			(fill no)
			(layer "F.Fab")
		)
		(pad "D" smd custom
			(at 0 -0.9525 180)
			(size 0.1905 0.1905)
			(layers "F.Cu" "F.Mask" "F.Paste")
			(net "LED_Q_12")
			(options
				(clearance outline)
				(anchor circle)
			)
			(primitives
				(gr_poly
					(pts
						(arc
							(start -0.1778 0.5715)
							(mid -0.321484 0.511984)
							(end -0.381 0.3683)
						)
						(arc
							(start -0.381 -0.3683)
							(mid -0.321484 -0.511984)
							(end -0.1778 -0.5715)
						)
						(arc
							(start 0.1778 -0.5715)
							(mid 0.321484 -0.511984)
							(end 0.381 -0.3683)
						)
						(arc
							(start 0.381 0.3683)
							(mid 0.321484 0.511984)
							(end 0.1778 0.5715)
						)
					)
					(width 0)
					(fill yes)
				)
			)
		)
		(pad "G" smd custom
			(at -0.98425 0.9525 180)
			(size 0.1905 0.1905)
			(layers "F.Cu" "F.Mask" "F.Paste")
			(net "VS4_LED_R")
			(options
				(clearance outline)
				(anchor circle)
			)
			(primitives
				(gr_poly
					(pts
						(arc
							(start -0.1778 0.5715)
							(mid -0.321484 0.511984)
							(end -0.381 0.3683)
						)
						(arc
							(start -0.381 -0.3683)
							(mid -0.321484 -0.511984)
							(end -0.1778 -0.5715)
						)
						(arc
							(start 0.1778 -0.5715)
							(mid 0.321484 -0.511984)
							(end 0.381 -0.3683)
						)
						(arc
							(start 0.381 0.3683)
							(mid 0.321484 0.511984)
							(end 0.1778 0.5715)
						)
					)
					(width 0)
					(fill yes)
				)
			)
		)
		(pad "S" smd custom
			(at 0.98425 0.9525 180)
			(size 0.1905 0.1905)
			(layers "F.Cu" "F.Mask" "F.Paste")
			(net "GND")
			(options
				(clearance outline)
				(anchor circle)
			)
			(primitives
				(gr_poly
					(pts
						(arc
							(start -0.1778 0.5715)
							(mid -0.321484 0.511984)
							(end -0.381 0.3683)
						)
						(arc
							(start -0.381 -0.3683)
							(mid -0.321484 -0.511984)
							(end -0.1778 -0.5715)
						)
						(arc
							(start 0.1778 -0.5715)
							(mid 0.321484 -0.511984)
							(end 0.381 -0.3683)
						)
						(arc
							(start 0.381 0.3683)
							(mid 0.321484 0.511984)
							(end 0.1778 0.5715)
						)
					)
					(width 0)
					(fill yes)
				)
			)
		)
	)
	(footprint ""
		(layer "F.Cu")
		(at 145.542 -95.25 90)
		(property "Reference" "PC93"
			(at 0 0 90)
			(layer "F.SilkS")
			(hide yes)
			(effects
				(font
					(size 1.27 1.27)
				)
			)
		)
		(property "Value" "SC22U6D3V5MX-5-GP"
			(at -0.0762 -6.1214 90)
			(unlocked yes)
			(layer "F.Fab")
			(hide yes)
			(effects
				(font
					(size 1.016 1.016)
					(thickness 0.1524)
				)
			)
		)
		(property "Device Type" "C805H56"
			(at -0.0762 -8.1534 90)
			(unlocked yes)
			(layer "F.Fab")
			(hide yes)
			(effects
				(font
					(size 1.016 1.016)
					(thickness 0.1524)
				)
			)
		)
		(duplicate_pad_numbers_are_jumpers no)
		(fp_line
			(start 0.635 0)
			(end -0.635 0)
			(stroke
				(width 0.508)
				(type default)
			)
			(layer "F.SilkS")
		)
		(fp_rect
			(start -0.9652 1.778)
			(end 0.9652 -1.778)
			(stroke
				(width 0)
				(type default)
			)
			(fill no)
			(layer "F.CrtYd")
		)
		(fp_poly
			(pts
				(xy -0.9652 -1.778) (xy 0.9652 -1.778) (xy 0.9652 1.778) (xy -0.9652 1.778)
			)
			(stroke
				(width 0)
				(type default)
			)
			(fill no)
			(layer "F.Fab")
		)
		(pad "1" smd rect
			(at 0 -0.9652 90)
			(size 1.397 1.143)
			(layers "F.Cu" "F.Mask" "F.Paste")
			(net "VR_P1V8_STBY_IN")
		)
		(pad "2" smd rect
			(at 0 0.9652 90)
			(size 1.397 1.143)
			(layers "F.Cu" "F.Mask" "F.Paste")
			(net "GND")
		)
	)
	(footprint ""
		(layer "F.Cu")
		(at 40.64 -206.883 180)
		(property "Reference" "R880"
			(at 0 0 180)
			(layer "F.SilkS")
			(hide yes)
			(effects
				(font
					(size 1.27 1.27)
				)
			)
		)
		(property "Value" "0R2J-2-GP"
			(at 0.064008 -3.993896 180)
			(unlocked yes)
			(layer "F.Fab")
			(hide yes)
			(effects
				(font
					(size 1.016 1.016)
					(thickness 0.1524)
				)
			)
		)
		(property "Device Type" "R402H16"
			(at 0.064008 -5.517896 180)
			(unlocked yes)
			(layer "F.Fab")
			(hide yes)
			(effects
				(font
					(size 1.016 1.016)
					(thickness 0.1524)
				)
			)
		)
		(duplicate_pad_numbers_are_jumpers no)
		(fp_line
			(start 0.508 -0.9398)
			(end -0.508 -0.9398)
			(stroke
				(width 0.1524)
				(type default)
			)
			(layer "F.SilkS")
		)
		(fp_line
			(start -0.508 -0.9398)
			(end -0.508 0.9398)
			(stroke
				(width 0.1524)
				(type default)
			)
			(layer "F.SilkS")
		)
		(fp_rect
			(start -0.508 0.9398)
			(end 0.508 -0.9398)
			(stroke
				(width 0)
				(type default)
			)
			(fill no)
			(layer "F.CrtYd")
		)
		(fp_rect
			(start -0.508 0.9398)
			(end 0.508 -0.9398)
			(stroke
				(width 0)
				(type default)
			)
			(fill no)
			(layer "F.Fab")
		)
		(pad "1" smd custom
			(at 0 -0.4445 180)
			(size 0.1397 0.1397)
			(layers "F.Cu" "F.Mask" "F.Paste")
			(net "BUF_I2C6_C_FCB_SDA_R")
			(options
				(clearance outline)
				(anchor circle)
			)
			(primitives
				(gr_poly
					(pts
						(arc
							(start -0.1778 -0.2794)
							(mid -0.249642 -0.249642)
							(end -0.2794 -0.1778)
						)
						(arc
							(start -0.2794 0.1778)
							(mid -0.249642 0.249642)
							(end -0.1778 0.2794)
						)
						(arc
							(start 0.1778 0.2794)
							(mid 0.249642 0.249642)
							(end 0.2794 0.1778)
						)
						(arc
							(start 0.2794 -0.1778)
							(mid 0.249642 -0.249642)
							(end 0.1778 -0.2794)
						)
					)
					(width 0)
					(fill yes)
				)
			)
		)
		(pad "2" smd custom
			(at 0 0.4445 180)
			(size 0.1397 0.1397)
			(layers "F.Cu" "F.Mask" "F.Paste")
			(net "BUF_I2C6_C_FCB_SDA")
			(options
				(clearance outline)
				(anchor circle)
			)
			(primitives
				(gr_poly
					(pts
						(arc
							(start -0.1778 -0.2794)
							(mid -0.249642 -0.249642)
							(end -0.2794 -0.1778)
						)
						(arc
							(start -0.2794 0.1778)
							(mid -0.249642 0.249642)
							(end -0.1778 0.2794)
						)
						(arc
							(start 0.1778 0.2794)
							(mid 0.249642 0.249642)
							(end 0.2794 0.1778)
						)
						(arc
							(start 0.2794 -0.1778)
							(mid 0.249642 -0.249642)
							(end 0.1778 -0.2794)
						)
					)
					(width 0)
					(fill yes)
				)
			)
		)
	)
	(footprint ""
		(layer "F.Cu")
		(at 346.324174 -61.089286 90)
		(property "Reference" "PC169"
			(at 0 0 90)
			(layer "F.SilkS")
			(hide yes)
			(effects
				(font
					(size 1.27 1.27)
				)
			)
		)
		(property "Value" "SC10U25V5KX-GP"
			(at -0.0762 -6.1214 90)
			(unlocked yes)
			(layer "F.Fab")
			(hide yes)
			(effects
				(font
					(size 1.016 1.016)
					(thickness 0.1524)
				)
			)
		)
		(property "Device Type" "C805H56"
			(at -0.0762 -8.1534 90)
			(unlocked yes)
			(layer "F.Fab")
			(hide yes)
			(effects
				(font
					(size 1.016 1.016)
					(thickness 0.1524)
				)
			)
		)
		(duplicate_pad_numbers_are_jumpers no)
		(fp_line
			(start 0.635 0)
			(end -0.635 0)
			(stroke
				(width 0.508)
				(type default)
			)
			(layer "F.SilkS")
		)
		(fp_rect
			(start -0.9652 1.778)
			(end 0.9652 -1.778)
			(stroke
				(width 0)
				(type default)
			)
			(fill no)
			(layer "F.CrtYd")
		)
		(fp_poly
			(pts
				(xy -0.9652 -1.778) (xy 0.9652 -1.778) (xy 0.9652 1.778) (xy -0.9652 1.778)
			)
			(stroke
				(width 0)
				(type default)
			)
			(fill no)
			(layer "F.Fab")
		)
		(pad "1" smd rect
			(at 0 -0.9652 90)
			(size 1.397 1.143)
			(layers "F.Cu" "F.Mask" "F.Paste")
			(net "P0V9_E_VIN")
		)
		(pad "2" smd rect
			(at 0 0.9652 90)
			(size 1.397 1.143)
			(layers "F.Cu" "F.Mask" "F.Paste")
			(net "GND")
		)
	)
	(footprint ""
		(layer "F.Cu")
		(at 26.035 -73.8886 90)
		(property "Reference" "R375"
			(at 0 0 90)
			(layer "F.SilkS")
			(hide yes)
			(effects
				(font
					(size 1.27 1.27)
				)
			)
		)
		(property "Value" "0R2J-2-GP"
			(at 0.064008 -3.993896 90)
			(unlocked yes)
			(layer "F.Fab")
			(hide yes)
			(effects
				(font
					(size 1.016 1.016)
					(thickness 0.1524)
				)
			)
		)
		(property "Device Type" "R402H16"
			(at 0.064008 -5.517896 90)
			(unlocked yes)
			(layer "F.Fab")
			(hide yes)
			(effects
				(font
					(size 1.016 1.016)
					(thickness 0.1524)
				)
			)
		)
		(duplicate_pad_numbers_are_jumpers no)
		(fp_line
			(start 0.508 -0.9398)
			(end -0.508 -0.9398)
			(stroke
				(width 0.1524)
				(type default)
			)
			(layer "F.SilkS")
		)
		(fp_line
			(start -0.508 -0.9398)
			(end -0.508 0.9398)
			(stroke
				(width 0.1524)
				(type default)
			)
			(layer "F.SilkS")
		)
		(fp_rect
			(start -0.508 0.9398)
			(end 0.508 -0.9398)
			(stroke
				(width 0)
				(type default)
			)
			(fill no)
			(layer "F.CrtYd")
		)
		(fp_rect
			(start -0.508 0.9398)
			(end 0.508 -0.9398)
			(stroke
				(width 0)
				(type default)
			)
			(fill no)
			(layer "F.Fab")
		)
		(pad "1" smd custom
			(at 0 -0.4445 90)
			(size 0.1397 0.1397)
			(layers "F.Cu" "F.Mask" "F.Paste")
			(net "RMII_PHY_BMC_RXD1_R")
			(options
				(clearance outline)
				(anchor circle)
			)
			(primitives
				(gr_poly
					(pts
						(arc
							(start -0.1778 -0.2794)
							(mid -0.249642 -0.249642)
							(end -0.2794 -0.1778)
						)
						(arc
							(start -0.2794 0.1778)
							(mid -0.249642 0.249642)
							(end -0.1778 0.2794)
						)
						(arc
							(start 0.1778 0.2794)
							(mid 0.249642 0.249642)
							(end 0.2794 0.1778)
						)
						(arc
							(start 0.2794 -0.1778)
							(mid 0.249642 -0.249642)
							(end 0.1778 -0.2794)
						)
					)
					(width 0)
					(fill yes)
				)
			)
		)
		(pad "2" smd custom
			(at 0 0.4445 90)
			(size 0.1397 0.1397)
			(layers "F.Cu" "F.Mask" "F.Paste")
			(net "RMII_PHY_BMC_RXD1")
			(options
				(clearance outline)
				(anchor circle)
			)
			(primitives
				(gr_poly
					(pts
						(arc
							(start -0.1778 -0.2794)
							(mid -0.249642 -0.249642)
							(end -0.2794 -0.1778)
						)
						(arc
							(start -0.2794 0.1778)
							(mid -0.249642 0.249642)
							(end -0.1778 0.2794)
						)
						(arc
							(start 0.1778 0.2794)
							(mid 0.249642 0.249642)
							(end 0.2794 0.1778)
						)
						(arc
							(start 0.2794 -0.1778)
							(mid 0.249642 -0.249642)
							(end 0.1778 -0.2794)
						)
					)
					(width 0)
					(fill yes)
				)
			)
		)
	)
	(footprint ""
		(layer "F.Cu")
		(at 62.611 -131.953 180)
		(property "Reference" "C8084"
			(at 0 0 180)
			(layer "F.SilkS")
			(hide yes)
			(effects
				(font
					(size 1.27 1.27)
				)
			)
		)
		(property "Value" "SCD1U25V2KX-2-GP"
			(at 1.1811 -2.7051 180)
			(unlocked yes)
			(layer "F.Fab")
			(hide yes)
			(effects
				(font
					(size 1.016 1.016)
					(thickness 0.1524)
				)
			)
		)
		(property "Device Type" "C402H22"
			(at 1.1811 -4.2291 180)
			(unlocked yes)
			(layer "F.Fab")
			(hide yes)
			(effects
				(font
					(size 1.016 1.016)
					(thickness 0.1524)
				)
			)
		)
		(duplicate_pad_numbers_are_jumpers no)
		(fp_rect
			(start -0.4318 0.9525)
			(end 0.4318 -0.9525)
			(stroke
				(width 0)
				(type default)
			)
			(fill no)
			(layer "F.CrtYd")
		)
		(fp_rect
			(start -0.4318 0.9525)
			(end 0.4318 -0.9525)
			(stroke
				(width 0)
				(type default)
			)
			(fill no)
			(layer "F.Fab")
		)
		(pad "1" smd custom
			(at 0 -0.4445 180)
			(size 0.1524 0.1524)
			(layers "F.Cu" "F.Mask" "F.Paste")
			(net "ADC_12V")
			(options
				(clearance outline)
				(anchor circle)
			)
			(primitives
				(gr_poly
					(pts
						(arc
							(start 0.3048 -0.2032)
							(mid 0.275042 -0.275042)
							(end 0.2032 -0.3048)
						)
						(arc
							(start -0.2032 -0.3048)
							(mid -0.275042 -0.275042)
							(end -0.3048 -0.2032)
						)
						(arc
							(start -0.3048 0.2032)
							(mid -0.275042 0.275042)
							(end -0.2032 0.3048)
						)
						(arc
							(start 0.2032 0.3048)
							(mid 0.275042 0.275042)
							(end 0.3048 0.2032)
						)
					)
					(width 0)
					(fill yes)
				)
			)
		)
		(pad "2" smd custom
			(at 0 0.4445 180)
			(size 0.1524 0.1524)
			(layers "F.Cu" "F.Mask" "F.Paste")
			(net "GND")
			(options
				(clearance outline)
				(anchor circle)
			)
			(primitives
				(gr_poly
					(pts
						(arc
							(start 0.3048 -0.2032)
							(mid 0.275042 -0.275042)
							(end 0.2032 -0.3048)
						)
						(arc
							(start -0.2032 -0.3048)
							(mid -0.275042 -0.275042)
							(end -0.3048 -0.2032)
						)
						(arc
							(start -0.3048 0.2032)
							(mid -0.275042 0.275042)
							(end -0.2032 0.3048)
						)
						(arc
							(start 0.2032 0.3048)
							(mid 0.275042 0.275042)
							(end 0.3048 0.2032)
						)
					)
					(width 0)
					(fill yes)
				)
			)
		)
	)
)
